(kicad_pcb
	(version 20260206)
	(generator "pcbnew")
	(generator_version "10.0")
	(general
		(thickness 1.6)
		(legacy_teardrops no)
	)
	(paper "A4")
	(title_block
		(title "9052_F0T_PDB_Converter_Brick_F_V03_1208_1600_OCP.brd")
		(comment 1 "Grand Teton / footprints 450-455 of 578")
	)
	(layers
		(0 "F.Cu" signal "TOP")
		(4 "In1.Cu" signal "GND")
		(6 "In2.Cu" signal "IN1")
		(8 "In3.Cu" signal "GND1")
		(10 "In4.Cu" signal "VCC")
		(12 "In5.Cu" signal "VCC1")
		(14 "In6.Cu" signal "GND2")
		(16 "In7.Cu" signal "IN2")
		(18 "In8.Cu" signal "GND3")
		(2 "B.Cu" signal "BOTTOM")
		(9 "F.Adhes" user "F.Adhesive")
		(11 "B.Adhes" user "B.Adhesive")
		(13 "F.Paste" user "Package Geometry/Pastemask Top")
		(15 "B.Paste" user "Package Geometry/Pastemask Bottom")
		(5 "F.SilkS" user "Ref Des/Silkscreen Top")
		(7 "B.SilkS" user "Ref Des/Silkscreen Bottom")
		(1 "F.Mask" user "Board Geometry/Soldermask Top")
		(3 "B.Mask" user "Board Geometry/Soldermask Bottom")
		(17 "Dwgs.User" user "User.Drawings")
		(19 "Cmts.User" user "User.Comments")
		(21 "Eco1.User" user "User.Eco1")
		(23 "Eco2.User" user "User.Eco2")
		(25 "Edge.Cuts" user "Board Geometry/Outline")
		(27 "Margin" user)
		(31 "F.CrtYd" user "Package Geometry/Place Bound Top")
		(29 "B.CrtYd" user "Package Geometry/Place Bound Bottom")
		(35 "F.Fab" user "Ref Des/Assembly Top")
		(33 "B.Fab" user "Ref Des/Assembly Bottom")
	)
	(footprint ""
		(layer "B.Cu")
		(at 58.928 -78.613)
		(property "Reference" "R183"
			(at 0 0 0)
			(layer "B.SilkS")
			(hide yes)
			(effects
				(font
					(size 1.27 1.27)
				)
				(justify mirror)
			)
		)
		(property "Value" ""
			(at 0 0 0)
			(layer "B.Fab")
			(effects
				(font
					(size 1.27 1.27)
				)
				(justify mirror)
			)
		)
		(duplicate_pad_numbers_are_jumpers no)
		(fp_line
			(start -0.7874 -0.4064)
			(end -0.7874 0.4064)
			(stroke
				(width 0.1524)
				(type default)
			)
			(layer "B.SilkS")
		)
		(fp_line
			(start -0.7874 0.4064)
			(end 0.7874 0.4064)
			(stroke
				(width 0.1524)
				(type default)
			)
			(layer "B.SilkS")
		)
		(fp_line
			(start 0.7874 -0.4064)
			(end -0.7874 -0.4064)
			(stroke
				(width 0.1524)
				(type default)
			)
			(layer "B.SilkS")
		)
		(fp_line
			(start 0.7874 0.4064)
			(end 0.7874 -0.4064)
			(stroke
				(width 0.1524)
				(type default)
			)
			(layer "B.SilkS")
		)
		(fp_line
			(start -0.67945 -0.3048)
			(end -0.67945 0.3048)
			(stroke
				(width 0.1)
				(type default)
			)
			(layer "B.Fab")
		)
		(fp_line
			(start -0.67945 0.3048)
			(end -0.120396 0.3048)
			(stroke
				(width 0.1)
				(type default)
			)
			(layer "B.Fab")
		)
		(fp_line
			(start -0.12065 -0.3048)
			(end -0.67945 -0.3048)
			(stroke
				(width 0.1)
				(type default)
			)
			(layer "B.Fab")
		)
		(fp_line
			(start -0.12065 -0.2794)
			(end -0.12065 -0.3048)
			(stroke
				(width 0.1)
				(type default)
			)
			(layer "B.Fab")
		)
		(fp_line
			(start -0.120396 0.2794)
			(end 0.12065 0.2794)
			(stroke
				(width 0.1)
				(type default)
			)
			(layer "B.Fab")
		)
		(fp_line
			(start -0.120396 0.3048)
			(end -0.120396 0.2794)
			(stroke
				(width 0.1)
				(type default)
			)
			(layer "B.Fab")
		)
		(fp_line
			(start 0.12065 -0.305054)
			(end 0.12065 -0.2794)
			(stroke
				(width 0.1)
				(type default)
			)
			(layer "B.Fab")
		)
		(fp_line
			(start 0.12065 -0.2794)
			(end -0.12065 -0.2794)
			(stroke
				(width 0.1)
				(type default)
			)
			(layer "B.Fab")
		)
		(fp_line
			(start 0.12065 0.2794)
			(end 0.12065 0.3048)
			(stroke
				(width 0.1)
				(type default)
			)
			(layer "B.Fab")
		)
		(fp_line
			(start 0.12065 0.3048)
			(end 0.67945 0.3048)
			(stroke
				(width 0.1)
				(type default)
			)
			(layer "B.Fab")
		)
		(fp_line
			(start 0.67945 -0.305054)
			(end 0.12065 -0.305054)
			(stroke
				(width 0.1)
				(type default)
			)
			(layer "B.Fab")
		)
		(fp_line
			(start 0.67945 0.3048)
			(end 0.67945 -0.305054)
			(stroke
				(width 0.1)
				(type default)
			)
			(layer "B.Fab")
		)
		(pad "1" smd circle
			(at 0.40005 0 180)
			(size 0 0)
			(layers "B.Cu" "B.Mask" "B.Paste")
			(net "P3V3_AUX")
		)
		(pad "2" smd circle
			(at -0.40005 0 180)
			(size 0 0)
			(layers "B.Cu" "B.Mask" "B.Paste")
			(net "SMB_P52V_VPDB_SCL")
		)
	)
	(footprint ""
		(layer "B.Cu")
		(at 281.432 -27.178 180)
		(property "Reference" "D11"
			(at 0.9271 -2.19837 0)
			(unlocked yes)
			(layer "B.SilkS")
			(effects
				(font
					(size 0.7874 0.5842)
					(thickness 0.1524)
				)
				(justify left mirror)
			)
		)
		(property "Value" ""
			(at 0 0 0)
			(layer "B.Fab")
			(effects
				(font
					(size 1.27 1.27)
				)
				(justify mirror)
			)
		)
		(duplicate_pad_numbers_are_jumpers no)
		(fp_line
			(start 3.400044 1.459992)
			(end 3.400044 -1.459992)
			(stroke
				(width 0.1524)
				(type default)
			)
			(layer "B.SilkS")
		)
		(fp_line
			(start 3.400044 -1.459992)
			(end -4.107942 -1.459992)
			(stroke
				(width 0.1524)
				(type default)
			)
			(layer "B.SilkS")
		)
		(fp_line
			(start -4.107942 1.459992)
			(end 3.400044 1.459992)
			(stroke
				(width 0.1524)
				(type default)
			)
			(layer "B.SilkS")
		)
		(fp_line
			(start -4.107942 -1.459992)
			(end -4.107942 1.459992)
			(stroke
				(width 0.1524)
				(type default)
			)
			(layer "B.SilkS")
		)
		(fp_poly
			(pts
				(xy -4.107942 -1.459992) (xy -4.107942 1.459992) (xy -3.308096 1.459992) (xy -3.308096 -1.459992)
			)
			(stroke
				(width 0)
				(type default)
			)
			(fill yes)
			(layer "B.SilkS")
		)
		(fp_line
			(start 2.29997 1.459992)
			(end 2.29997 -1.459992)
			(stroke
				(width 0.1)
				(type default)
			)
			(layer "B.Fab")
		)
		(fp_line
			(start 2.29997 -1.459992)
			(end -2.29997 -1.459992)
			(stroke
				(width 0.1)
				(type default)
			)
			(layer "B.Fab")
		)
		(fp_line
			(start -2.29997 1.459992)
			(end 2.29997 1.459992)
			(stroke
				(width 0.1)
				(type default)
			)
			(layer "B.Fab")
		)
		(fp_line
			(start -2.29997 -1.459992)
			(end -2.29997 1.459992)
			(stroke
				(width 0.1)
				(type default)
			)
			(layer "B.Fab")
		)
		(fp_text user "+"
			(at 4.7752 -0.12065 180)
			(unlocked yes)
			(layer "B.SilkS")
			(effects
				(font
					(size 1.905 1.4224)
					(thickness 0.1524)
				)
				(justify left mirror)
			)
		)
		(fp_text user "-"
			(at -5.4102 0.29845 0)
			(unlocked yes)
			(layer "B.SilkS")
			(effects
				(font
					(size 1.905 1.4224)
					(thickness 0.1524)
				)
				(justify left mirror)
			)
		)
		(fp_text user "+"
			(at 4.7752 -0.12065 180)
			(unlocked yes)
			(layer "B.Fab")
			(effects
				(font
					(size 1.905 1.4224)
					(thickness 0.1524)
				)
				(justify left mirror)
			)
		)
		(fp_text user "-"
			(at -5.4102 0.29845 0)
			(unlocked yes)
			(layer "B.Fab")
			(effects
				(font
					(size 1.905 1.4224)
					(thickness 0.1524)
				)
				(justify left mirror)
			)
		)
		(pad "A" smd rect
			(at 1.999996 0 270)
			(size 1.7018 2.5146)
			(layers "B.Cu" "B.Mask" "B.Paste")
			(net "FM_AC_PWR_CYCLE_R_BUF")
		)
		(pad "C" smd rect
			(at -1.999996 0 270)
			(size 1.7018 2.5146)
			(layers "B.Cu" "B.Mask" "B.Paste")
			(net "FM_AC_PWR_CYCLE_BUF")
		)
	)
	(footprint ""
		(layer "B.Cu")
		(at 233.553 -70.993 90)
		(property "Reference" "R139"
			(at 0 0 90)
			(layer "B.SilkS")
			(hide yes)
			(effects
				(font
					(size 1.27 1.27)
				)
				(justify mirror)
			)
		)
		(property "Value" ""
			(at 0 0 90)
			(layer "B.Fab")
			(effects
				(font
					(size 1.27 1.27)
				)
				(justify mirror)
			)
		)
		(duplicate_pad_numbers_are_jumpers no)
		(fp_line
			(start 0.7874 -0.4064)
			(end -0.7874 -0.4064)
			(stroke
				(width 0.1524)
				(type default)
			)
			(layer "B.SilkS")
		)
		(fp_line
			(start -0.7874 -0.4064)
			(end -0.7874 0.4064)
			(stroke
				(width 0.1524)
				(type default)
			)
			(layer "B.SilkS")
		)
		(fp_line
			(start 0.7874 0.4064)
			(end 0.7874 -0.4064)
			(stroke
				(width 0.1524)
				(type default)
			)
			(layer "B.SilkS")
		)
		(fp_line
			(start -0.7874 0.4064)
			(end 0.7874 0.4064)
			(stroke
				(width 0.1524)
				(type default)
			)
			(layer "B.SilkS")
		)
		(fp_line
			(start 0.67945 -0.305054)
			(end 0.12065 -0.305054)
			(stroke
				(width 0.1)
				(type default)
			)
			(layer "B.Fab")
		)
		(fp_line
			(start 0.12065 -0.305054)
			(end 0.12065 -0.2794)
			(stroke
				(width 0.1)
				(type default)
			)
			(layer "B.Fab")
		)
		(fp_line
			(start -0.12065 -0.3048)
			(end -0.67945 -0.3048)
			(stroke
				(width 0.1)
				(type default)
			)
			(layer "B.Fab")
		)
		(fp_line
			(start -0.67945 -0.3048)
			(end -0.67945 0.3048)
			(stroke
				(width 0.1)
				(type default)
			)
			(layer "B.Fab")
		)
		(fp_line
			(start 0.12065 -0.2794)
			(end -0.12065 -0.2794)
			(stroke
				(width 0.1)
				(type default)
			)
			(layer "B.Fab")
		)
		(fp_line
			(start -0.12065 -0.2794)
			(end -0.12065 -0.3048)
			(stroke
				(width 0.1)
				(type default)
			)
			(layer "B.Fab")
		)
		(fp_line
			(start 0.12065 0.2794)
			(end 0.12065 0.3048)
			(stroke
				(width 0.1)
				(type default)
			)
			(layer "B.Fab")
		)
		(fp_line
			(start -0.120396 0.2794)
			(end 0.12065 0.2794)
			(stroke
				(width 0.1)
				(type default)
			)
			(layer "B.Fab")
		)
		(fp_line
			(start 0.67945 0.3048)
			(end 0.67945 -0.305054)
			(stroke
				(width 0.1)
				(type default)
			)
			(layer "B.Fab")
		)
		(fp_line
			(start 0.12065 0.3048)
			(end 0.67945 0.3048)
			(stroke
				(width 0.1)
				(type default)
			)
			(layer "B.Fab")
		)
		(fp_line
			(start -0.120396 0.3048)
			(end -0.120396 0.2794)
			(stroke
				(width 0.1)
				(type default)
			)
			(layer "B.Fab")
		)
		(fp_line
			(start -0.67945 0.3048)
			(end -0.120396 0.3048)
			(stroke
				(width 0.1)
				(type default)
			)
			(layer "B.Fab")
		)
		(pad "1" smd circle
			(at 0.40005 0 270)
			(size 0 0)
			(layers "B.Cu" "B.Mask" "B.Paste")
			(net "PWRGD_P3V3_AUX_MB")
		)
		(pad "2" smd circle
			(at -0.40005 0 270)
			(size 0 0)
			(layers "B.Cu" "B.Mask" "B.Paste")
			(net "PWRGD_P3V3_AUX_MB_R")
		)
	)
	(footprint ""
		(layer "B.Cu")
		(at 219.964 -95.504 90)
		(property "Reference" "C40"
			(at 0 0 90)
			(layer "B.SilkS")
			(hide yes)
			(effects
				(font
					(size 1.27 1.27)
				)
				(justify mirror)
			)
		)
		(property "Value" ""
			(at 0 0 90)
			(layer "B.Fab")
			(effects
				(font
					(size 1.27 1.27)
				)
				(justify mirror)
			)
		)
		(duplicate_pad_numbers_are_jumpers no)
		(fp_line
			(start 2.2098 -0.9398)
			(end -2.2098 -0.9398)
			(stroke
				(width 0.1524)
				(type default)
			)
			(layer "B.SilkS")
		)
		(fp_line
			(start -2.2098 -0.9398)
			(end -2.2098 0.9398)
			(stroke
				(width 0.1524)
				(type default)
			)
			(layer "B.SilkS")
		)
		(fp_line
			(start 2.2098 0.9398)
			(end 2.2098 -0.9398)
			(stroke
				(width 0.1524)
				(type default)
			)
			(layer "B.SilkS")
		)
		(fp_line
			(start -2.2098 0.9398)
			(end 2.2098 0.9398)
			(stroke
				(width 0.1524)
				(type default)
			)
			(layer "B.SilkS")
		)
		(fp_line
			(start 1.700022 -0.899922)
			(end -1.700022 -0.899922)
			(stroke
				(width 0.1)
				(type default)
			)
			(layer "B.Fab")
		)
		(fp_line
			(start -1.700022 -0.899922)
			(end -1.700022 0.899922)
			(stroke
				(width 0.1)
				(type default)
			)
			(layer "B.Fab")
		)
		(fp_line
			(start 1.700022 0.899922)
			(end 1.700022 -0.899922)
			(stroke
				(width 0.1)
				(type default)
			)
			(layer "B.Fab")
		)
		(fp_line
			(start -1.700022 0.899922)
			(end 1.700022 0.899922)
			(stroke
				(width 0.1)
				(type default)
			)
			(layer "B.Fab")
		)
		(pad "1" smd rect
			(at 1.4732 0 90)
			(size 1.1684 1.5748)
			(layers "B.Cu" "B.Mask" "B.Paste")
			(net "P52V_HS")
		)
		(pad "2" smd rect
			(at -1.4732 0 90)
			(size 1.1684 1.5748)
			(layers "B.Cu" "B.Mask" "B.Paste")
			(net "GND")
		)
	)
	(footprint ""
		(layer "B.Cu")
		(at 205.994 -69.723 90)
		(property "Reference" "C4"
			(at 0 0 90)
			(layer "B.SilkS")
			(hide yes)
			(effects
				(font
					(size 1.27 1.27)
				)
				(justify mirror)
			)
		)
		(property "Value" ""
			(at 0 0 90)
			(layer "B.Fab")
			(effects
				(font
					(size 1.27 1.27)
				)
				(justify mirror)
			)
		)
		(duplicate_pad_numbers_are_jumpers no)
		(fp_line
			(start 0.7874 -0.4064)
			(end -0.7874 -0.4064)
			(stroke
				(width 0.1524)
				(type default)
			)
			(layer "B.SilkS")
		)
		(fp_line
			(start -0.7874 -0.4064)
			(end -0.7874 0.4064)
			(stroke
				(width 0.1524)
				(type default)
			)
			(layer "B.SilkS")
		)
		(fp_line
			(start 0.7874 0.4064)
			(end 0.7874 -0.4064)
			(stroke
				(width 0.1524)
				(type default)
			)
			(layer "B.SilkS")
		)
		(fp_line
			(start -0.7874 0.4064)
			(end 0.7874 0.4064)
			(stroke
				(width 0.1524)
				(type default)
			)
			(layer "B.SilkS")
		)
		(fp_line
			(start 0.67945 -0.305054)
			(end 0.12065 -0.305054)
			(stroke
				(width 0.1)
				(type default)
			)
			(layer "B.Fab")
		)
		(fp_line
			(start 0.12065 -0.305054)
			(end 0.12065 -0.2794)
			(stroke
				(width 0.1)
				(type default)
			)
			(layer "B.Fab")
		)
		(fp_line
			(start -0.12065 -0.3048)
			(end -0.67945 -0.3048)
			(stroke
				(width 0.1)
				(type default)
			)
			(layer "B.Fab")
		)
		(fp_line
			(start -0.67945 -0.3048)
			(end -0.67945 0.3048)
			(stroke
				(width 0.1)
				(type default)
			)
			(layer "B.Fab")
		)
		(fp_line
			(start 0.12065 -0.2794)
			(end -0.12065 -0.2794)
			(stroke
				(width 0.1)
				(type default)
			)
			(layer "B.Fab")
		)
		(fp_line
			(start -0.12065 -0.2794)
			(end -0.12065 -0.3048)
			(stroke
				(width 0.1)
				(type default)
			)
			(layer "B.Fab")
		)
		(fp_line
			(start 0.12065 0.2794)
			(end 0.12065 0.3048)
			(stroke
				(width 0.1)
				(type default)
			)
			(layer "B.Fab")
		)
		(fp_line
			(start -0.120396 0.2794)
			(end 0.12065 0.2794)
			(stroke
				(width 0.1)
				(type default)
			)
			(layer "B.Fab")
		)
		(fp_line
			(start 0.67945 0.3048)
			(end 0.67945 -0.305054)
			(stroke
				(width 0.1)
				(type default)
			)
			(layer "B.Fab")
		)
		(fp_line
			(start 0.12065 0.3048)
			(end 0.67945 0.3048)
			(stroke
				(width 0.1)
				(type default)
			)
			(layer "B.Fab")
		)
		(fp_line
			(start -0.120396 0.3048)
			(end -0.120396 0.2794)
			(stroke
				(width 0.1)
				(type default)
			)
			(layer "B.Fab")
		)
		(fp_line
			(start -0.67945 0.3048)
			(end -0.120396 0.3048)
			(stroke
				(width 0.1)
				(type default)
			)
			(layer "B.Fab")
		)
		(pad "1" smd circle
			(at 0.40005 0 270)
			(size 0 0)
			(layers "B.Cu" "B.Mask" "B.Paste")
			(net "P3V3_AUX")
		)
		(pad "2" smd circle
			(at -0.40005 0 270)
			(size 0 0)
			(layers "B.Cu" "B.Mask" "B.Paste")
			(net "GND")
		)
	)
	(footprint ""
		(layer "B.Cu")
		(at 206.121 -82.55 90)
		(property "Reference" "R17"
			(at 0 0 90)
			(layer "B.SilkS")
			(hide yes)
			(effects
				(font
					(size 1.27 1.27)
				)
				(justify mirror)
			)
		)
		(property "Value" ""
			(at 0 0 90)
			(layer "B.Fab")
			(effects
				(font
					(size 1.27 1.27)
				)
				(justify mirror)
			)
		)
		(duplicate_pad_numbers_are_jumpers no)
		(fp_line
			(start 0.7874 -0.4064)
			(end -0.7874 -0.4064)
			(stroke
				(width 0.1524)
				(type default)
			)
			(layer "B.SilkS")
		)
		(fp_line
			(start -0.7874 -0.4064)
			(end -0.7874 0.4064)
			(stroke
				(width 0.1524)
				(type default)
			)
			(layer "B.SilkS")
		)
		(fp_line
			(start 0.7874 0.4064)
			(end 0.7874 -0.4064)
			(stroke
				(width 0.1524)
				(type default)
			)
			(layer "B.SilkS")
		)
		(fp_line
			(start -0.7874 0.4064)
			(end 0.7874 0.4064)
			(stroke
				(width 0.1524)
				(type default)
			)
			(layer "B.SilkS")
		)
		(fp_line
			(start 0.67945 -0.305054)
			(end 0.12065 -0.305054)
			(stroke
				(width 0.1)
				(type default)
			)
			(layer "B.Fab")
		)
		(fp_line
			(start 0.12065 -0.305054)
			(end 0.12065 -0.2794)
			(stroke
				(width 0.1)
				(type default)
			)
			(layer "B.Fab")
		)
		(fp_line
			(start -0.12065 -0.3048)
			(end -0.67945 -0.3048)
			(stroke
				(width 0.1)
				(type default)
			)
			(layer "B.Fab")
		)
		(fp_line
			(start -0.67945 -0.3048)
			(end -0.67945 0.3048)
			(stroke
				(width 0.1)
				(type default)
			)
			(layer "B.Fab")
		)
		(fp_line
			(start 0.12065 -0.2794)
			(end -0.12065 -0.2794)
			(stroke
				(width 0.1)
				(type default)
			)
			(layer "B.Fab")
		)
		(fp_line
			(start -0.12065 -0.2794)
			(end -0.12065 -0.3048)
			(stroke
				(width 0.1)
				(type default)
			)
			(layer "B.Fab")
		)
		(fp_line
			(start 0.12065 0.2794)
			(end 0.12065 0.3048)
			(stroke
				(width 0.1)
				(type default)
			)
			(layer "B.Fab")
		)
		(fp_line
			(start -0.120396 0.2794)
			(end 0.12065 0.2794)
			(stroke
				(width 0.1)
				(type default)
			)
			(layer "B.Fab")
		)
		(fp_line
			(start 0.67945 0.3048)
			(end 0.67945 -0.305054)
			(stroke
				(width 0.1)
				(type default)
			)
			(layer "B.Fab")
		)
		(fp_line
			(start 0.12065 0.3048)
			(end 0.67945 0.3048)
			(stroke
				(width 0.1)
				(type default)
			)
			(layer "B.Fab")
		)
		(fp_line
			(start -0.120396 0.3048)
			(end -0.120396 0.2794)
			(stroke
				(width 0.1)
				(type default)
			)
			(layer "B.Fab")
		)
		(fp_line
			(start -0.67945 0.3048)
			(end -0.120396 0.3048)
			(stroke
				(width 0.1)
				(type default)
			)
			(layer "B.Fab")
		)
		(pad "1" smd circle
			(at 0.40005 0 270)
			(size 0 0)
			(layers "B.Cu" "B.Mask" "B.Paste")
			(net "P3V3_AUX")
		)
		(pad "2" smd circle
			(at -0.40005 0 270)
			(size 0 0)
			(layers "B.Cu" "B.Mask" "B.Paste")
			(net "PU_U4_PIN1")
		)
	)
)
